(kicad_pcb
	(version 20260206)
	(generator "pcbnew")
	(generator_version "10.0")
	(general
		(thickness 1.6)
		(legacy_teardrops no)
	)
	(paper "A4")
	(title_block
		(title "04192023_DAF0TMB3IC0_F0TG_MB_C_brd_V02_OCP.brd")
		(comment 1 "Grand Teton / footprints 6440-6446 of 8354")
	)
	(layers
		(0 "F.Cu" signal "TOP")
		(4 "In1.Cu" signal "GND")
		(6 "In2.Cu" signal "IN1")
		(8 "In3.Cu" signal "GND1")
		(10 "In4.Cu" signal "IN2")
		(12 "In5.Cu" signal "GND2")
		(14 "In6.Cu" signal "IN3")
		(16 "In7.Cu" signal "GND3")
		(18 "In8.Cu" signal "VCC")
		(20 "In9.Cu" signal "VCC1")
		(22 "In10.Cu" signal "GND4")
		(24 "In11.Cu" signal "IN4")
		(26 "In12.Cu" signal "GND5")
		(28 "In13.Cu" signal "IN5")
		(30 "In14.Cu" signal "GND6")
		(32 "In15.Cu" signal "IN6")
		(34 "In16.Cu" signal "GND7")
		(2 "B.Cu" signal "BOTTOM")
		(9 "F.Adhes" user "F.Adhesive")
		(11 "B.Adhes" user "B.Adhesive")
		(13 "F.Paste" user "Package Geometry/Pastemask Top")
		(15 "B.Paste" user "Package Geometry/Pastemask Bottom")
		(5 "F.SilkS" user "Ref Des/Silkscreen Top")
		(7 "B.SilkS" user "Ref Des/Silkscreen Bottom")
		(1 "F.Mask" user "Board Geometry/Soldermask Top")
		(3 "B.Mask" user "Board Geometry/Soldermask Bottom")
		(17 "Dwgs.User" user "User.Drawings")
		(19 "Cmts.User" user "User.Comments")
		(21 "Eco1.User" user "User.Eco1")
		(23 "Eco2.User" user "User.Eco2")
		(25 "Edge.Cuts" user "Board Geometry/Outline")
		(27 "Margin" user)
		(31 "F.CrtYd" user "Package Geometry/Place Bound Top")
		(29 "B.CrtYd" user "Package Geometry/Place Bound Bottom")
		(35 "F.Fab" user "Ref Des/Assembly Top")
		(33 "B.Fab" user "Ref Des/Assembly Bottom")
	)
	(footprint ""
		(layer "B.Cu")
		(at 46.308518 -346.788994 90)
		(property "Reference" "PC443_2"
			(at 0 0 90)
			(layer "B.SilkS")
			(hide yes)
			(effects
				(font
					(size 1.27 1.27)
				)
				(justify mirror)
			)
		)
		(property "Value" ""
			(at 0 0 90)
			(layer "B.Fab")
			(effects
				(font
					(size 1.27 1.27)
				)
				(justify mirror)
			)
		)
		(duplicate_pad_numbers_are_jumpers no)
		(fp_line
			(start 1.524 -0.762)
			(end -1.524 -0.762)
			(stroke
				(width 0.1524)
				(type default)
			)
			(layer "B.SilkS")
		)
		(fp_line
			(start -1.524 -0.762)
			(end -1.524 0.762)
			(stroke
				(width 0.1524)
				(type default)
			)
			(layer "B.SilkS")
		)
		(fp_line
			(start 1.524 0.762)
			(end 1.524 -0.762)
			(stroke
				(width 0.1524)
				(type default)
			)
			(layer "B.SilkS")
		)
		(fp_line
			(start -1.524 0.762)
			(end 1.524 0.762)
			(stroke
				(width 0.1524)
				(type default)
			)
			(layer "B.SilkS")
		)
		(fp_line
			(start 1.1049 -0.724916)
			(end 1.1049 0.724916)
			(stroke
				(width 0.1)
				(type default)
			)
			(layer "B.Fab")
		)
		(fp_line
			(start -1.1049 -0.724916)
			(end 1.1049 -0.724916)
			(stroke
				(width 0.1)
				(type default)
			)
			(layer "B.Fab")
		)
		(fp_line
			(start 1.1049 0.724916)
			(end -1.1049 0.724916)
			(stroke
				(width 0.1)
				(type default)
			)
			(layer "B.Fab")
		)
		(fp_line
			(start -1.1049 0.724916)
			(end -1.1049 -0.724916)
			(stroke
				(width 0.1)
				(type default)
			)
			(layer "B.Fab")
		)
		(pad "1" smd rect
			(at 0.889 0 90)
			(size 1.016 1.27)
			(layers "B.Cu" "B.Mask" "B.Paste")
			(net "SW_P12V_AUX_PVDDIO_P1_FLT")
		)
		(pad "2" smd rect
			(at -0.889 0 90)
			(size 1.016 1.27)
			(layers "B.Cu" "B.Mask" "B.Paste")
			(net "GND")
		)
	)
	(footprint ""
		(layer "B.Cu")
		(at 320.17843 -395.148562 90)
		(property "Reference" "C573"
			(at 0 0 90)
			(layer "B.SilkS")
			(hide yes)
			(effects
				(font
					(size 1.27 1.27)
				)
				(justify mirror)
			)
		)
		(property "Value" ""
			(at 0 0 90)
			(layer "B.Fab")
			(effects
				(font
					(size 1.27 1.27)
				)
				(justify mirror)
			)
		)
		(duplicate_pad_numbers_are_jumpers no)
		(fp_line
			(start 0.299974 -0.150114)
			(end -0.299974 -0.150114)
			(stroke
				(width 0.1)
				(type default)
			)
			(layer "B.Fab")
		)
		(fp_line
			(start -0.299974 -0.150114)
			(end -0.299974 0.150114)
			(stroke
				(width 0.1)
				(type default)
			)
			(layer "B.Fab")
		)
		(fp_line
			(start 0.299974 0.150114)
			(end 0.299974 -0.150114)
			(stroke
				(width 0.1)
				(type default)
			)
			(layer "B.Fab")
		)
		(fp_line
			(start -0.299974 0.150114)
			(end 0.299974 0.150114)
			(stroke
				(width 0.1)
				(type default)
			)
			(layer "B.Fab")
		)
		(pad "1" smd rect
			(at 0.2667 0 270)
			(size 0.3048 0.381)
			(layers "B.Cu" "B.Mask" "B.Paste")
			(net "P0V9_CPU0_RT0_2A")
		)
		(pad "2" smd rect
			(at -0.2667 0 270)
			(size 0.3048 0.381)
			(layers "B.Cu" "B.Mask" "B.Paste")
			(net "GND")
		)
	)
	(footprint ""
		(layer "B.Cu")
		(at 100.496878 -139.93241 90)
		(property "Reference" "PC10"
			(at 0 0 90)
			(layer "B.SilkS")
			(hide yes)
			(effects
				(font
					(size 1.27 1.27)
				)
				(justify mirror)
			)
		)
		(property "Value" ""
			(at 0 0 90)
			(layer "B.Fab")
			(effects
				(font
					(size 1.27 1.27)
				)
				(justify mirror)
			)
		)
		(duplicate_pad_numbers_are_jumpers no)
		(fp_line
			(start 0.7874 -0.4064)
			(end -0.7874 -0.4064)
			(stroke
				(width 0.1524)
				(type default)
			)
			(layer "B.SilkS")
		)
		(fp_line
			(start -0.7874 -0.4064)
			(end -0.7874 0.4064)
			(stroke
				(width 0.1524)
				(type default)
			)
			(layer "B.SilkS")
		)
		(fp_line
			(start 0.7874 0.4064)
			(end 0.7874 -0.4064)
			(stroke
				(width 0.1524)
				(type default)
			)
			(layer "B.SilkS")
		)
		(fp_line
			(start -0.7874 0.4064)
			(end 0.7874 0.4064)
			(stroke
				(width 0.1524)
				(type default)
			)
			(layer "B.SilkS")
		)
		(fp_line
			(start 0.67945 -0.305054)
			(end 0.12065 -0.305054)
			(stroke
				(width 0.1)
				(type default)
			)
			(layer "B.Fab")
		)
		(fp_line
			(start 0.12065 -0.305054)
			(end 0.12065 -0.2794)
			(stroke
				(width 0.1)
				(type default)
			)
			(layer "B.Fab")
		)
		(fp_line
			(start -0.12065 -0.3048)
			(end -0.67945 -0.3048)
			(stroke
				(width 0.1)
				(type default)
			)
			(layer "B.Fab")
		)
		(fp_line
			(start -0.67945 -0.3048)
			(end -0.67945 0.3048)
			(stroke
				(width 0.1)
				(type default)
			)
			(layer "B.Fab")
		)
		(fp_line
			(start 0.12065 -0.2794)
			(end -0.12065 -0.2794)
			(stroke
				(width 0.1)
				(type default)
			)
			(layer "B.Fab")
		)
		(fp_line
			(start -0.12065 -0.2794)
			(end -0.12065 -0.3048)
			(stroke
				(width 0.1)
				(type default)
			)
			(layer "B.Fab")
		)
		(fp_line
			(start 0.12065 0.2794)
			(end 0.12065 0.3048)
			(stroke
				(width 0.1)
				(type default)
			)
			(layer "B.Fab")
		)
		(fp_line
			(start -0.120396 0.2794)
			(end 0.12065 0.2794)
			(stroke
				(width 0.1)
				(type default)
			)
			(layer "B.Fab")
		)
		(fp_line
			(start 0.67945 0.3048)
			(end 0.67945 -0.305054)
			(stroke
				(width 0.1)
				(type default)
			)
			(layer "B.Fab")
		)
		(fp_line
			(start 0.12065 0.3048)
			(end 0.67945 0.3048)
			(stroke
				(width 0.1)
				(type default)
			)
			(layer "B.Fab")
		)
		(fp_line
			(start -0.120396 0.3048)
			(end -0.120396 0.2794)
			(stroke
				(width 0.1)
				(type default)
			)
			(layer "B.Fab")
		)
		(fp_line
			(start -0.67945 0.3048)
			(end -0.120396 0.3048)
			(stroke
				(width 0.1)
				(type default)
			)
			(layer "B.Fab")
		)
		(pad "1" smd circle
			(at 0.40005 0 270)
			(size 0 0)
			(layers "B.Cu" "B.Mask" "B.Paste")
			(net "PVDDCR_CPU0_P1_VCC")
		)
		(pad "2" smd circle
			(at -0.40005 0 270)
			(size 0 0)
			(layers "B.Cu" "B.Mask" "B.Paste")
			(net "GND")
		)
	)
	(footprint ""
		(layer "B.Cu")
		(at 374.0912 -398.942052 90)
		(property "Reference" "C1049"
			(at 0 0 90)
			(layer "B.SilkS")
			(hide yes)
			(effects
				(font
					(size 1.27 1.27)
				)
				(justify mirror)
			)
		)
		(property "Value" ""
			(at 0 0 90)
			(layer "B.Fab")
			(effects
				(font
					(size 1.27 1.27)
				)
				(justify mirror)
			)
		)
		(duplicate_pad_numbers_are_jumpers no)
		(fp_line
			(start 0.7874 -0.4064)
			(end -0.7874 -0.4064)
			(stroke
				(width 0.1524)
				(type default)
			)
			(layer "B.SilkS")
		)
		(fp_line
			(start -0.7874 -0.4064)
			(end -0.7874 0.4064)
			(stroke
				(width 0.1524)
				(type default)
			)
			(layer "B.SilkS")
		)
		(fp_line
			(start 0.7874 0.4064)
			(end 0.7874 -0.4064)
			(stroke
				(width 0.1524)
				(type default)
			)
			(layer "B.SilkS")
		)
		(fp_line
			(start -0.7874 0.4064)
			(end 0.7874 0.4064)
			(stroke
				(width 0.1524)
				(type default)
			)
			(layer "B.SilkS")
		)
		(fp_line
			(start 0.67945 -0.305054)
			(end 0.12065 -0.305054)
			(stroke
				(width 0.1)
				(type default)
			)
			(layer "B.Fab")
		)
		(fp_line
			(start 0.12065 -0.305054)
			(end 0.12065 -0.2794)
			(stroke
				(width 0.1)
				(type default)
			)
			(layer "B.Fab")
		)
		(fp_line
			(start -0.12065 -0.3048)
			(end -0.67945 -0.3048)
			(stroke
				(width 0.1)
				(type default)
			)
			(layer "B.Fab")
		)
		(fp_line
			(start -0.67945 -0.3048)
			(end -0.67945 0.3048)
			(stroke
				(width 0.1)
				(type default)
			)
			(layer "B.Fab")
		)
		(fp_line
			(start 0.12065 -0.2794)
			(end -0.12065 -0.2794)
			(stroke
				(width 0.1)
				(type default)
			)
			(layer "B.Fab")
		)
		(fp_line
			(start -0.12065 -0.2794)
			(end -0.12065 -0.3048)
			(stroke
				(width 0.1)
				(type default)
			)
			(layer "B.Fab")
		)
		(fp_line
			(start 0.12065 0.2794)
			(end 0.12065 0.3048)
			(stroke
				(width 0.1)
				(type default)
			)
			(layer "B.Fab")
		)
		(fp_line
			(start -0.120396 0.2794)
			(end 0.12065 0.2794)
			(stroke
				(width 0.1)
				(type default)
			)
			(layer "B.Fab")
		)
		(fp_line
			(start 0.67945 0.3048)
			(end 0.67945 -0.305054)
			(stroke
				(width 0.1)
				(type default)
			)
			(layer "B.Fab")
		)
		(fp_line
			(start 0.12065 0.3048)
			(end 0.67945 0.3048)
			(stroke
				(width 0.1)
				(type default)
			)
			(layer "B.Fab")
		)
		(fp_line
			(start -0.120396 0.3048)
			(end -0.120396 0.2794)
			(stroke
				(width 0.1)
				(type default)
			)
			(layer "B.Fab")
		)
		(fp_line
			(start -0.67945 0.3048)
			(end -0.120396 0.3048)
			(stroke
				(width 0.1)
				(type default)
			)
			(layer "B.Fab")
		)
		(pad "1" smd circle
			(at 0.40005 0 270)
			(size 0 0)
			(layers "B.Cu" "B.Mask" "B.Paste")
			(net "P0V9_CPU0_RT3_2A")
		)
		(pad "2" smd circle
			(at -0.40005 0 270)
			(size 0 0)
			(layers "B.Cu" "B.Mask" "B.Paste")
			(net "GND")
		)
	)
	(footprint ""
		(layer "B.Cu")
		(at 51.766978 -431.904902 90)
		(property "Reference" "C1974"
			(at 0 0 90)
			(layer "B.SilkS")
			(hide yes)
			(effects
				(font
					(size 1.27 1.27)
				)
				(justify mirror)
			)
		)
		(property "Value" ""
			(at 0 0 90)
			(layer "B.Fab")
			(effects
				(font
					(size 1.27 1.27)
				)
				(justify mirror)
			)
		)
		(duplicate_pad_numbers_are_jumpers no)
		(fp_line
			(start 0.7874 -0.4064)
			(end -0.7874 -0.4064)
			(stroke
				(width 0.1524)
				(type default)
			)
			(layer "B.SilkS")
		)
		(fp_line
			(start -0.7874 -0.4064)
			(end -0.7874 0.4064)
			(stroke
				(width 0.1524)
				(type default)
			)
			(layer "B.SilkS")
		)
		(fp_line
			(start 0.7874 0.4064)
			(end 0.7874 -0.4064)
			(stroke
				(width 0.1524)
				(type default)
			)
			(layer "B.SilkS")
		)
		(fp_line
			(start -0.7874 0.4064)
			(end 0.7874 0.4064)
			(stroke
				(width 0.1524)
				(type default)
			)
			(layer "B.SilkS")
		)
		(fp_line
			(start 0.67945 -0.305054)
			(end 0.12065 -0.305054)
			(stroke
				(width 0.1)
				(type default)
			)
			(layer "B.Fab")
		)
		(fp_line
			(start 0.12065 -0.305054)
			(end 0.12065 -0.2794)
			(stroke
				(width 0.1)
				(type default)
			)
			(layer "B.Fab")
		)
		(fp_line
			(start -0.12065 -0.3048)
			(end -0.67945 -0.3048)
			(stroke
				(width 0.1)
				(type default)
			)
			(layer "B.Fab")
		)
		(fp_line
			(start -0.67945 -0.3048)
			(end -0.67945 0.3048)
			(stroke
				(width 0.1)
				(type default)
			)
			(layer "B.Fab")
		)
		(fp_line
			(start 0.12065 -0.2794)
			(end -0.12065 -0.2794)
			(stroke
				(width 0.1)
				(type default)
			)
			(layer "B.Fab")
		)
		(fp_line
			(start -0.12065 -0.2794)
			(end -0.12065 -0.3048)
			(stroke
				(width 0.1)
				(type default)
			)
			(layer "B.Fab")
		)
		(fp_line
			(start 0.12065 0.2794)
			(end 0.12065 0.3048)
			(stroke
				(width 0.1)
				(type default)
			)
			(layer "B.Fab")
		)
		(fp_line
			(start -0.120396 0.2794)
			(end 0.12065 0.2794)
			(stroke
				(width 0.1)
				(type default)
			)
			(layer "B.Fab")
		)
		(fp_line
			(start 0.67945 0.3048)
			(end 0.67945 -0.305054)
			(stroke
				(width 0.1)
				(type default)
			)
			(layer "B.Fab")
		)
		(fp_line
			(start 0.12065 0.3048)
			(end 0.67945 0.3048)
			(stroke
				(width 0.1)
				(type default)
			)
			(layer "B.Fab")
		)
		(fp_line
			(start -0.120396 0.3048)
			(end -0.120396 0.2794)
			(stroke
				(width 0.1)
				(type default)
			)
			(layer "B.Fab")
		)
		(fp_line
			(start -0.67945 0.3048)
			(end -0.120396 0.3048)
			(stroke
				(width 0.1)
				(type default)
			)
			(layer "B.Fab")
		)
		(pad "1" smd circle
			(at 0.40005 0 270)
			(size 0 0)
			(layers "B.Cu" "B.Mask" "B.Paste")
			(net "GPU_FPGA_THERM_OVERT_ISO_N")
		)
		(pad "2" smd circle
			(at -0.40005 0 270)
			(size 0 0)
			(layers "B.Cu" "B.Mask" "B.Paste")
			(net "GND")
		)
	)
	(footprint ""
		(layer "B.Cu")
		(at 235.839 -241.2111 90)
		(property "Reference" "R337"
			(at 0 0 90)
			(layer "B.SilkS")
			(hide yes)
			(effects
				(font
					(size 1.27 1.27)
				)
				(justify mirror)
			)
		)
		(property "Value" ""
			(at 0 0 90)
			(layer "B.Fab")
			(effects
				(font
					(size 1.27 1.27)
				)
				(justify mirror)
			)
		)
		(duplicate_pad_numbers_are_jumpers no)
		(fp_line
			(start 0.7874 -0.4064)
			(end -0.7874 -0.4064)
			(stroke
				(width 0.1524)
				(type default)
			)
			(layer "B.SilkS")
		)
		(fp_line
			(start -0.7874 -0.4064)
			(end -0.7874 0.4064)
			(stroke
				(width 0.1524)
				(type default)
			)
			(layer "B.SilkS")
		)
		(fp_line
			(start 0.7874 0.4064)
			(end 0.7874 -0.4064)
			(stroke
				(width 0.1524)
				(type default)
			)
			(layer "B.SilkS")
		)
		(fp_line
			(start -0.7874 0.4064)
			(end 0.7874 0.4064)
			(stroke
				(width 0.1524)
				(type default)
			)
			(layer "B.SilkS")
		)
		(fp_line
			(start 0.67945 -0.305054)
			(end 0.12065 -0.305054)
			(stroke
				(width 0.1)
				(type default)
			)
			(layer "B.Fab")
		)
		(fp_line
			(start 0.12065 -0.305054)
			(end 0.12065 -0.2794)
			(stroke
				(width 0.1)
				(type default)
			)
			(layer "B.Fab")
		)
		(fp_line
			(start -0.12065 -0.3048)
			(end -0.67945 -0.3048)
			(stroke
				(width 0.1)
				(type default)
			)
			(layer "B.Fab")
		)
		(fp_line
			(start -0.67945 -0.3048)
			(end -0.67945 0.3048)
			(stroke
				(width 0.1)
				(type default)
			)
			(layer "B.Fab")
		)
		(fp_line
			(start 0.12065 -0.2794)
			(end -0.12065 -0.2794)
			(stroke
				(width 0.1)
				(type default)
			)
			(layer "B.Fab")
		)
		(fp_line
			(start -0.12065 -0.2794)
			(end -0.12065 -0.3048)
			(stroke
				(width 0.1)
				(type default)
			)
			(layer "B.Fab")
		)
		(fp_line
			(start 0.12065 0.2794)
			(end 0.12065 0.3048)
			(stroke
				(width 0.1)
				(type default)
			)
			(layer "B.Fab")
		)
		(fp_line
			(start -0.120396 0.2794)
			(end 0.12065 0.2794)
			(stroke
				(width 0.1)
				(type default)
			)
			(layer "B.Fab")
		)
		(fp_line
			(start 0.67945 0.3048)
			(end 0.67945 -0.305054)
			(stroke
				(width 0.1)
				(type default)
			)
			(layer "B.Fab")
		)
		(fp_line
			(start 0.12065 0.3048)
			(end 0.67945 0.3048)
			(stroke
				(width 0.1)
				(type default)
			)
			(layer "B.Fab")
		)
		(fp_line
			(start -0.120396 0.3048)
			(end -0.120396 0.2794)
			(stroke
				(width 0.1)
				(type default)
			)
			(layer "B.Fab")
		)
		(fp_line
			(start -0.67945 0.3048)
			(end -0.120396 0.3048)
			(stroke
				(width 0.1)
				(type default)
			)
			(layer "B.Fab")
		)
		(pad "1" smd rect
			(at 0.40005 0 90)
			(size 0.4572 0.508)
			(layers "B.Cu" "B.Mask" "B.Paste")
			(net "SMB_APML_CPU1_MUX2_SCL")
		)
		(pad "2" smd rect
			(at -0.40005 0 90)
			(size 0.4572 0.508)
			(layers "B.Cu" "B.Mask" "B.Paste")
			(net "SMB_APML_CPU1_SCL")
		)
	)
	(footprint ""
		(layer "B.Cu")
		(at 61.791342 -390.560052 90)
		(property "Reference" "C286"
			(at 0 0 90)
			(layer "B.SilkS")
			(hide yes)
			(effects
				(font
					(size 1.27 1.27)
				)
				(justify mirror)
			)
		)
		(property "Value" ""
			(at 0 0 90)
			(layer "B.Fab")
			(effects
				(font
					(size 1.27 1.27)
				)
				(justify mirror)
			)
		)
		(duplicate_pad_numbers_are_jumpers no)
		(fp_line
			(start 0.7874 -0.4064)
			(end -0.7874 -0.4064)
			(stroke
				(width 0.1524)
				(type default)
			)
			(layer "B.SilkS")
		)
		(fp_line
			(start -0.7874 -0.4064)
			(end -0.7874 0.4064)
			(stroke
				(width 0.1524)
				(type default)
			)
			(layer "B.SilkS")
		)
		(fp_line
			(start 0.7874 0.4064)
			(end 0.7874 -0.4064)
			(stroke
				(width 0.1524)
				(type default)
			)
			(layer "B.SilkS")
		)
		(fp_line
			(start -0.7874 0.4064)
			(end 0.7874 0.4064)
			(stroke
				(width 0.1524)
				(type default)
			)
			(layer "B.SilkS")
		)
		(fp_line
			(start 0.67945 -0.305054)
			(end 0.12065 -0.305054)
			(stroke
				(width 0.1)
				(type default)
			)
			(layer "B.Fab")
		)
		(fp_line
			(start 0.12065 -0.305054)
			(end 0.12065 -0.2794)
			(stroke
				(width 0.1)
				(type default)
			)
			(layer "B.Fab")
		)
		(fp_line
			(start -0.12065 -0.3048)
			(end -0.67945 -0.3048)
			(stroke
				(width 0.1)
				(type default)
			)
			(layer "B.Fab")
		)
		(fp_line
			(start -0.67945 -0.3048)
			(end -0.67945 0.3048)
			(stroke
				(width 0.1)
				(type default)
			)
			(layer "B.Fab")
		)
		(fp_line
			(start 0.12065 -0.2794)
			(end -0.12065 -0.2794)
			(stroke
				(width 0.1)
				(type default)
			)
			(layer "B.Fab")
		)
		(fp_line
			(start -0.12065 -0.2794)
			(end -0.12065 -0.3048)
			(stroke
				(width 0.1)
				(type default)
			)
			(layer "B.Fab")
		)
		(fp_line
			(start 0.12065 0.2794)
			(end 0.12065 0.3048)
			(stroke
				(width 0.1)
				(type default)
			)
			(layer "B.Fab")
		)
		(fp_line
			(start -0.120396 0.2794)
			(end 0.12065 0.2794)
			(stroke
				(width 0.1)
				(type default)
			)
			(layer "B.Fab")
		)
		(fp_line
			(start 0.67945 0.3048)
			(end 0.67945 -0.305054)
			(stroke
				(width 0.1)
				(type default)
			)
			(layer "B.Fab")
		)
		(fp_line
			(start 0.12065 0.3048)
			(end 0.67945 0.3048)
			(stroke
				(width 0.1)
				(type default)
			)
			(layer "B.Fab")
		)
		(fp_line
			(start -0.120396 0.3048)
			(end -0.120396 0.2794)
			(stroke
				(width 0.1)
				(type default)
			)
			(layer "B.Fab")
		)
		(fp_line
			(start -0.67945 0.3048)
			(end -0.120396 0.3048)
			(stroke
				(width 0.1)
				(type default)
			)
			(layer "B.Fab")
		)
		(pad "1" smd circle
			(at 0.40005 0 270)
			(size 0 0)
			(layers "B.Cu" "B.Mask" "B.Paste")
			(net "P0V9_CPU1_RT0_2A")
		)
		(pad "2" smd circle
			(at -0.40005 0 270)
			(size 0 0)
			(layers "B.Cu" "B.Mask" "B.Paste")
			(net "GND")
		)
	)
)
